FILE_TYPE = CONNECTIVITY;
{Allegro Design Entry HDL 17.2-2016 S081 (4005846) 1/11/2022}
"PAGE_NUMBER" = 297;
0"NC";
1"P3V3_AUX\g";
2"P12V_E1S_0\g";
3"P3V3_AUX\g";
4"P3V3_E1S_0\g";
5"P3V3_E1S_0\g";
6"P12V_E1S_0\g";
7"P3V3_AUX\g";
8"P3V3_AUX\g";
9"P3V3_AUX\g";
10"P3V3_AUX\g";
11"P3V3_E1S_0\g";
12"P3V3_E1S_0\g";
13"P3V3_E1S_0\g";
14"P3V3_E1S_0\g";
15"GND\g";
16"GND\g";
17"GND\g";
18"GND\g";
19"GND\g";
20"GND\g";
21"GND\g";
22"GND\g";
23"GND\g";
24"GND\g";
25"GND\g";
26"GND\g";
27"GND\g";
28"GND\g";
29"P3E_PCH_E1S_RX_DP<3:0>";
30"P3E_PCH_E1S_TX_C_DP<3:0>";
31"P3E_PCH_E1S_TX_C_DN<3:0>";
32"P3E_PCH_E1S_RX_DN<3:0>";
33"E1S_0_PRSNT_N";
34"E1S_0_PERST1_CLKREQ_N";
35"TP_CLK_100M_E1S_0_DN";
36"E1S_0_LED_ACT_N";
37"SMB_E1S_3V3AUX_ISO_SDA";
38"SMB_E1S_3V3AUX_ISO_SCL";
39"RST_SMB_E1S_0_N";
40"TP_E1S_0_RFU";
41"TP_E1S_0_MFG";
42"PU_E1S_0_DUALPORT_EN_N";
43"RST_PCIE_PCH_E1S_PERST_N";
44"E1S_0_PWRDIS";
45"TP_CLK_100M_E1S_0_DP";
46"P3E_PCH_E1S_RX_DP<0>";
47"P3E_PCH_E1S_RX_DN<0>";
48"P3E_PCH_E1S_RX_DP<1>";
49"HP_E1S_0_P3V3_PWRGD";
50"HP_E1S_0_P3V3_PWRGD_PLD";
51"E1S_0_PWRDIS";
52"FM_PS_EN_PLD_BUF1";
53"FM_PS_EN_PLD_BUF1_R1";
54"E1S_0_EN"$PHYS_NET_NAME"RST_PCIE_M2_N"CDS_PHYS_NET_NAME"E1S_0_EN";
55"E1S_0_PRSNT_N";
56"E1S_0_PRSNT";
57"P3E_PCH_E1S_TX_C_DN<1>";
58"P3E_PCH_E1S_RX_DN<2>";
59"RST_SMB_E1S_N"CDS_PHYS_NET_NAME"RST_PCIE_PCH_DEV_PERST_N";
60"CLK_100M_E1S_0_DP";
61"CLK_100M_E1S_0_DN";
62"P3E_PCH_E1S_TX_C_DN<2>";
63"P3E_PCH_E1S_RX_DN<3>";
64"P3E_PCH_E1S_RX_DP<3>";
65"P3E_PCH_E1S_RX_DN<1>";
66"RST_SMB_E1S_0_N";
67"RST_PCIE_PCH_DEV_PERST_E1S_R_N";
68"P3E_PCH_E1S_TX_C_DP<3>";
69"P3E_PCH_E1S_TX_C_DP<2>";
70"RST_SMB_SWITCH_N"CDS_PHYS_NET_NAME"RST_SMB_SWITCH_N";
71"RST_SMB_BUF_E1S_0_N"CDS_PHYS_NET_NAME"RST_PCIE_CPU0_BUF_E1S_0_PERST_N";
72"SMB_PCIE_E1S_ISO_EN_R2"CDS_PHYS_NET_NAME"RST_PCIE_CPU0_BUF_E1S_1_PERST_N";
73"SMB_PCIE_E1S_ISO_EN";
74"P3E_PCH_E1S_TX_C_DN<3>";
75"P3E_PCH_E1S_TX_C_DP<1>";
76"P3E_PCH_E1S_TX_C_DN<0>";
77"P3E_PCH_E1S_TX_C_DP<0>";
78"P3E_PCH_E1S_RX_DP<2>";
%"Q_RES"
"1","(2275,825)","0","pure_quanta","I157";
;
PART_NUMBER"CS00002JB13"
VALUE"0"
TOLERANCE"5%"
MATERIAL"CHIP"
$LOCATION"R2350"
CDS_LIB"pure_quanta"
WATTAGE"1/16W"
PACK_TYPE"0402LF"
CDS_LOCATION"R2350"
$SEC"1"
CDS_SEC"1";
"B"
$PN"2"53;
"A"
$PN"1"52;
%"Q_RES"
"2","(1800,1525)","2","pure_quanta","I159";
;
PART_NUMBER"CS31002FB08"
PACK_TYPE"0402LF"
TOLERANCE"1%"
WATTAGE"1/16W"
MATERIAL"CHIP"
VALUE"10K"
$LOCATION"R2304"
CDS_LIB"pure_quanta"
CDS_LOCATION"R2304"
$SEC"1"
CDS_SEC"1";
"A"
$PN"1"9;
"B"
$PN"2"55;
%"UNIVERSAL_POWER"
"1","(1800,1775)","0","logical_power","I160";
;
HDL_POWER"P3V3_AUX"
CDS_LIB"logical_power";
"A"9;
%"74LVC1G126SE7"
"1","(3675,875)","0","pure_quanta","I163";
;
PART_NUMBER"AL1G0126009"
MATERIAL"IC"
PART_TYPE"SMLF"
VALUE"74LVC1G126SE-7"
$LOCATION"U145"
SEC_TYPE""
CDS_LIB"pure_quanta"
CDS_LMAN_SYM_OUTLINE"-100,100,100,-100"
NEEDS_NO_SIZE"TRUE"
CDS_LOCATION"U145"
SEC"1";
"OE"
$PN"1"53;
"GND"
$PN"3"22;
"VCC"
$PN"5"7;
"Y"
$PN"4"54;
"A"
$PN"2"56;
%"UNIVERSAL_GND"
"1","(3675,475)","0","logical_power","I164";
;
HDL_POWER"GND"
CDS_LIB"logical_power";
"A"22;
%"Q_RES"
"2","(4350,650)","0","pure_quanta","I165";
;
PART_NUMBER"CS41002FB09"
PACK_TYPE"0402LF"
VALUE"100K"
WATTAGE"1/16W"
MATERIAL"CHIP"
TOLERANCE"1%"
$LOCATION"R2457"
CDS_LIB"pure_quanta"
CDS_LOCATION"R2457"
$SEC"1"
CDS_SEC"1";
"A"
$PN"1"54;
"B"
$PN"2"23;
%"UNIVERSAL_GND"
"1","(4350,450)","0","logical_power","I166";
;
HDL_POWER"GND"
CDS_LIB"logical_power";
"A"23;
%"UNIVERSAL_POWER"
"1","(2675,2000)","0","logical_power","I168";
;
HDL_POWER"P3V3_AUX"
CDS_LIB"logical_power";
"A"8;
%"Q_RES"
"2","(2675,1800)","0","pure_quanta","I169";
;
PART_NUMBER"CS31002FB08"
VALUE"10K"
TOLERANCE"1%"
WATTAGE"1/16W"
MATERIAL"CHIP"
PACK_TYPE"0402LF"
$LOCATION"R2282"
CDS_LIB"pure_quanta"
CDS_LOCATION"R2282"
$SEC"1"
CDS_SEC"1";
"A"
$PN"1"8;
"B"
$PN"2"56;
%"Q_CAP"
"1","(3850,1400)","0","pure_quanta","I170";
;
PART_NUMBER"CH4104K1B00"
PACK_TYPE"0402"
VOLTAGE"25V"
VALUE"0.1UF"
TOLERANCE"10%"
MATERIAL"X7R"
$LOCATION"C1614"
CDS_LIB"pure_quanta"
CDS_LOCATION"C1614"
$SEC"1"
CDS_SEC"1";
"B"
$PN"2"24;
"A"
$PN"1"7;
%"UNIVERSAL_GND"
"1","(3850,1175)","0","logical_power","I171";
;
HDL_POWER"GND"
CDS_LIB"logical_power";
"A"24;
%"UNIVERSAL_POWER"
"1","(3850,1675)","0","logical_power","I172";
;
HDL_POWER"P3V3_AUX"
CDS_LIB"logical_power";
"A"7;
%"Q_CAP"
"1","(2600,2825)","0","pure_quanta","I237";
;
PART_NUMBER"CH6223MEA01"
PACK_TYPE"C0805"
VALUE"22UF"
VOLTAGE"16V"
MATERIAL"X6S"
TOLERANCE"20%"
$LOCATION"C1277"
CDS_LIB"pure_quanta"
CDS_LOCATION"C1277"
$SEC"1"
CDS_SEC"1";
"B"
$PN"2"20;
"A"
$PN"1"2;
%"UNIVERSAL_POWER"
"1","(3775,4850)","0","logical_power","I238";
;
HDL_POWER"P3V3_E1S_0"
CDS_LIB"logical_power";
"A"14;
%"UNIVERSAL_POWER"
"1","(2300,4825)","0","logical_power","I242";
;
HDL_POWER"P3V3_E1S_0"
CDS_LIB"logical_power";
"A"12;
%"Q_CAP"
"1","(4600,2825)","0","pure_quanta","I245";
;
PART_NUMBER"CH4104K1B00"
VALUE"0.1UF"
VOLTAGE"25V"
MATERIAL"X7R"
PACK_TYPE"0402"
TOLERANCE"10%"
$LOCATION"C1283"
CDS_LIB"pure_quanta"
CDS_LOCATION"C1283"
$SEC"1"
CDS_SEC"1";
"B"
$PN"2"21;
"A"
$PN"1"5;
%"UNIVERSAL_POWER"
"1","(4350,3175)","0","logical_power","I246";
;
HDL_POWER"P3V3_E1S_0"
CDS_LIB"logical_power";
"A"5;
%"Q_CAP"
"1","(4350,2825)","0","pure_quanta","I247";
;
PART_NUMBER"CH4104K1B00"
VOLTAGE"25V"
VALUE"0.1UF"
PACK_TYPE"0402"
MATERIAL"X7R"
TOLERANCE"10%"
$LOCATION"C1282"
CDS_LIB"pure_quanta"
CDS_LOCATION"C1282"
$SEC"1"
CDS_SEC"1";
"B"
$PN"2"21;
"A"
$PN"1"5;
%"UNIVERSAL_GND"
"1","(4600,2475)","0","logical_power","I248";
;
CDS_LIB"logical_power"
HDL_POWER"GND"
ROOM"IO_SLOT";
"A"21;
%"UNIVERSAL_GND"
"1","(3850,3625)","0","logical_power","I250";
;
CDS_LIB"logical_power"
HDL_POWER"GND"
ROOM"IO_SLOT";
"A"15;
%"Q_CAP"
"1","(3275,2825)","0","pure_quanta","I252";
;
PART_NUMBER"CH4104K1B00"
PACK_TYPE"0402"
VALUE"0.1UF"
VOLTAGE"25V"
MATERIAL"X7R"
TOLERANCE"10%"
$LOCATION"C1279"
CDS_LIB"pure_quanta"
CDS_LOCATION"C1279"
$SEC"1"
CDS_SEC"1";
"B"
$PN"2"20;
"A"
$PN"1"2;
%"UNIVERSAL_GND"
"1","(3275,2475)","0","logical_power","I253";
;
CDS_LIB"logical_power"
HDL_POWER"GND"
ROOM"IO_SLOT";
"A"20;
%"Q_CAP"
"1","(3000,2825)","0","pure_quanta","I258";
;
PART_NUMBER"CH4104K1B00"
VALUE"0.1UF"
MATERIAL"X7R"
TOLERANCE"10%"
VOLTAGE"25V"
PACK_TYPE"0402"
$LOCATION"C1278"
CDS_LIB"pure_quanta"
CDS_LOCATION"C1278"
$SEC"1"
CDS_SEC"1";
"B"
$PN"2"20;
"A"
$PN"1"2;
%"UNIVERSAL_POWER"
"1","(2325,3175)","0","logical_power","I259";
;
HDL_POWER"P12V_E1S_0"
CDS_LIB"logical_power";
"A"2;
%"Q_CAP"
"1","(2325,2825)","0","pure_quanta","I260";
;
PART_NUMBER"CH6223MEA01"
MATERIAL"X6S"
VOLTAGE"16V"
PACK_TYPE"C0805"
TOLERANCE"20%"
VALUE"22UF"
$LOCATION"C1276"
CDS_LIB"pure_quanta"
CDS_LOCATION"C1276"
$SEC"1"
CDS_SEC"1";
"B"
$PN"2"20;
"A"
$PN"1"2;
%"UNIVERSAL_POWER"
"1","(-350,5175)","0","logical_power","I261";
;
HDL_POWER"P12V_E1S_0"
CDS_LIB"logical_power";
"A"6;
%"UNIVERSAL_POWER"
"1","(-650,5000)","0","logical_power","I262";
;
HDL_POWER"P3V3_E1S_0"
CDS_LIB"logical_power";
"A"4;
%"UNIVERSAL_POWER"
"1","(-1925,4775)","0","logical_power","I263";
;
HDL_POWER"P3V3_E1S_0"
CDS_LIB"logical_power";
"A"13;
%"Q_RES"
"2","(-1925,4525)","0","pure_quanta","I264";
;
PART_NUMBER"CS31002FB08"
PACK_TYPE"0402LF"
MATERIAL"CHIP"
VALUE"10K"
TOLERANCE"1%"
WATTAGE"1/16W"
LOCATION"R2317"
CDS_LIB"pure_quanta"
$SEC"1"
CDS_SEC"1";
"A"
$PN"1"13;
"B"
$PN"2"42;
%"TAP"
"1","(1825,3650)","0","standard","I267";
;
CDS_LIB"standard"
BODY_TYPE"PLUMBING"
HDL_TAP"TRUE";
"B \NAC \NWC"32;
"S \NAC"
BN"1"65;
%"TAP"
"1","(1825,3500)","0","standard","I268";
;
CDS_LIB"standard"
BODY_TYPE"PLUMBING"
HDL_TAP"TRUE";
"B \NAC \NWC"32;
"S \NAC"
BN"2"58;
%"TAP"
"1","(1675,3600)","0","standard","I269";
;
CDS_LIB"standard"
BODY_TYPE"PLUMBING"
HDL_TAP"TRUE";
"B \NAC \NWC"29;
"S \NAC"
BN"1"48;
%"TAP"
"1","(1675,3450)","0","standard","I270";
;
CDS_LIB"standard"
BODY_TYPE"PLUMBING"
HDL_TAP"TRUE";
"B \NAC \NWC"29;
"S \NAC"
BN"2"78;
%"TAP"
"1","(1825,3350)","0","standard","I271";
;
CDS_LIB"standard"
BODY_TYPE"PLUMBING"
HDL_TAP"TRUE";
"B \NAC \NWC"32;
"S \NAC"
BN"3"63;
%"TAP"
"1","(1675,3300)","0","standard","I272";
;
CDS_LIB"standard"
BODY_TYPE"PLUMBING"
HDL_TAP"TRUE";
"B \NAC \NWC"29;
"S \NAC"
BN"3"64;
%"UNIVERSAL_GND"
"1","(1400,2950)","0","logical_power","I273";
;
CDS_LIB"logical_power"
HDL_POWER"GND"
ROOM"IO_SLOT";
"A"16;
%"UNIVERSAL_GND"
"1","(-400,2950)","0","logical_power","I275";
;
CDS_LIB"logical_power"
HDL_POWER"GND"
ROOM"IO_SLOT";
"A"17;
%"TAP"
"1","(-625,3450)","2","standard","I278";
;
CDS_LIB"standard"
BODY_TYPE"PLUMBING"
HDL_TAP"TRUE";
"B \NAC \NWC"30;
"S \NAC"
BN"2"69;
%"TAP"
"1","(-625,3300)","2","standard","I280";
;
CDS_LIB"standard"
BODY_TYPE"PLUMBING"
HDL_TAP"TRUE";
"B \NAC \NWC"30;
"S \NAC"
BN"3"68;
%"TAP"
"1","(-775,3500)","2","standard","I281";
;
CDS_LIB"standard"
BODY_TYPE"PLUMBING"
HDL_TAP"TRUE";
"B \NAC \NWC"31;
"S \NAC"
BN"2"62;
%"TAP"
"1","(-775,3350)","2","standard","I283";
;
CDS_LIB"standard"
BODY_TYPE"PLUMBING"
HDL_TAP"TRUE";
"B \NAC \NWC"31;
"S \NAC"
BN"3"74;
%"UNIVERSAL_POWER"
"1","(-3475,3700)","0","logical_power","I290";
;
HDL_POWER"P3V3_AUX"
CDS_LIB"logical_power";
"A"10;
%"Q_RES"
"2","(-3475,3450)","0","pure_quanta","I291";
;
PART_NUMBER"CS31002FB08"
VALUE"10K"
PACK_TYPE"0402LF"
MATERIAL"CHIP"
WATTAGE"1/16W"
TOLERANCE"1%"
$LOCATION"R3771"
CDS_LIB"pure_quanta"
CDS_LOCATION"R3771"
$SEC"1"
CDS_SEC"1";
"A"
$PN"1"10;
"B"
$PN"2"51;
%"Q_RES"
"2","(-3475,2950)","0","pure_quanta","I293";
;
PART_NUMBER"CS21002FB06"
PACK_TYPE"0402LF"
VALUE"1K"
MATERIAL"CHIP"
WATTAGE"1/16W"
TOLERANCE"1%"
LOCATION"R2296"
CDS_LIB"pure_quanta"
$SEC"1"
CDS_SEC"1";
"A"
$PN"1"51;
"B"
$PN"2"26;
%"UNIVERSAL_GND"
"1","(-3475,2700)","0","logical_power","I294";
;
CDS_LIB"logical_power"
HDL_POWER"GND";
"A"26;
%"UNIVERSAL_POWER"
"1","(2775,150)","0","logical_power","I295";
;
HDL_POWER"P3V3_AUX"
CDS_LIB"logical_power";
"A"3;
%"Q_RES"
"2","(3050,-200)","0","pure_quanta","I296";
;
PART_NUMBER"CS24702JB10"
TOLERANCE"5%"
VALUE"4.7K"
PACK_TYPE"0402LF"
MATERIAL"CHIP"
WATTAGE"1/16W"
$LOCATION"R2125"
CDS_LIB"pure_quanta"
CDS_LOCATION"R2125"
$SEC"1"
CDS_SEC"1";
"A"
$PN"1"3;
"B"
$PN"2"73;
%"Q_RES"
"2","(2775,-200)","0","pure_quanta","I299";
;
PART_NUMBER"CS24702JB10"
VALUE"4.7K"
WATTAGE"1/16W"
TOLERANCE"5%"
PACK_TYPE"0402LF"
MATERIAL"EMPTY"
$LOCATION"R3773"
CDS_LIB"pure_quanta"
CDS_LOCATION"R3773"
$SEC"1"
CDS_SEC"1";
"A"
$PN"1"3;
"B"
$PN"2"66;
%"UNIVERSAL_POWER"
"1","(950,125)","0","logical_power","I300";
;
HDL_POWER"P3V3_AUX"
CDS_LIB"logical_power";
"A"1;
%"Q_RES"
"1","(1750,-550)","0","pure_quanta","I301";
;
PART_NUMBER"CS00002JB13"
PACK_TYPE"0402LF"
VALUE"0"
TOLERANCE"5%"
MATERIAL"CHIP"
WATTAGE"1/16W"
$LOCATION"R3772"
CDS_LIB"pure_quanta"
CDS_LOCATION"R3772"
$SEC"1"
CDS_SEC"1";
"B"
$PN"2"66;
"A"
$PN"1"71;
%"Q_RES"
"1","(1750,-650)","0","pure_quanta","I302";
;
PART_NUMBER"CS00002JB13"
VALUE"0"
TOLERANCE"5%"
MATERIAL"CHIP"
$LOCATION"R2114"
WATTAGE"1/16W"
PACK_TYPE"0402LF"
CDS_LIB"pure_quanta"
CDS_LOCATION"R2114"
$SEC"1"
CDS_SEC"1";
"B"
$PN"2"73;
"A"
$PN"1"72;
%"UNIVERSAL_GND"
"1","(950,-425)","0","logical_power","I303";
;
CDS_LIB"logical_power"
HDL_POWER"GND";
"A"19;
%"Q_CAP"
"1","(950,-200)","0","pure_quanta","I304";
;
PART_NUMBER"CH4104K1B00"
TOLERANCE"10%"
VOLTAGE"25V"
VALUE"0.1UF"
MATERIAL"X7R"
PACK_TYPE"0402"
$LOCATION"C1592"
CDS_LIB"pure_quanta"
CDS_LOCATION"C1592"
$SEC"1"
CDS_SEC"1";
"B"
$PN"2"19;
"A"
$PN"1"1;
%"74LVC2G07DW7"
"1","(250,-600)","0","pure_quanta","I305";
;
PART_NUMBER"AL002G07003"
VALUE"74LVC2G07DW-7"
PART_TYPE"SMLF"
MATERIAL"IC"
LOCATION"U134"
NEEDS_NO_SIZE"TRUE"
CDS_LMAN_SYM_OUTLINE"-175,100,175,-100"
CDS_LIB"pure_quanta"
$SEC"1"
CDS_SEC"1";
"VCC"
$PN"5"1;
"GND"
$PN"2"18;
"2Y"
$PN"4"72;
"1Y"
$PN"6"71;
"2A"
$PN"3"59;
"1A"
$PN"1"59;
%"UNIVERSAL_GND"
"1","(-175,-825)","0","logical_power","I306";
;
CDS_LIB"logical_power"
HDL_POWER"GND";
"A"18;
%"Q_RES"
"1","(-1000,-550)","0","pure_quanta","I307";
;
PART_NUMBER"CS00002JB13"
TOLERANCE"5%"
VALUE"0"
MATERIAL"CHIP"
$LOCATION"R3775"
CDS_LIB"pure_quanta"
PACK_TYPE"0402LF"
WATTAGE"1/16W"
CDS_LOCATION"R3775"
$SEC"1"
CDS_SEC"1";
"B"
$PN"2"59;
"A"
$PN"1"70;
%"Q_RES"
"1","(-2000,4200)","0","pure_quanta","I309";
;
PART_NUMBER"CS00002JB13"
PACK_TYPE"0402LF"
VALUE"0"
MATERIAL"CHIP"
WATTAGE"1/16W"
TOLERANCE"5%"
$LOCATION"R3779"
CDS_LIB"pure_quanta"
CDS_LOCATION"R3779"
$SEC"1"
CDS_SEC"1";
"B"
$PN"2"43;
"A"
$PN"1"67;
%"Q_RES"
"2","(3850,3850)","0","pure_quanta","I311";
;
PART_NUMBER"CS11002FB07"
VALUE"100"
PACK_TYPE"0402LF"
MATERIAL"EMPTY"
WATTAGE"1/16W"
TOLERANCE"1%"
LOCATION"R2426"
CDS_LIB"pure_quanta"
$SEC"1"
CDS_SEC"1";
"A"
$PN"1"34;
"B"
$PN"2"15;
%"Q_RES"
"2","(2300,4625)","0","pure_quanta","I312";
;
PART_NUMBER"CS31002FB08"
MATERIAL"CHIP"
PACK_TYPE"0402LF"
VALUE"10K"
TOLERANCE"1%"
WATTAGE"1/16W"
LOCATION"R1673"
CDS_LIB"pure_quanta"
$SEC"1"
CDS_SEC"1";
"A"
$PN"1"12;
"B"
$PN"2"39;
%"Q_RES"
"2","(3775,4650)","0","pure_quanta","I313";
;
PART_NUMBER"CS31002FB08"
WATTAGE"1/16W"
TOLERANCE"1%"
MATERIAL"CHIP"
VALUE"10K"
PACK_TYPE"0402LF"
LOCATION"R2287"
CDS_LIB"pure_quanta"
$SEC"1"
CDS_SEC"1";
"A"
$PN"1"14;
"B"
$PN"2"34;
%"MOSFET_NCH_GDS_ESD_PROTECTED"
"1","(2650,1225)","0","pure_quanta","I316";
;
PART_NUMBER"BAM70020002"
PART_TYPE"SMLF"
VALUE"2N7002K"
MATERIAL"IC"
LOCATION"Q46"
NEEDS_NO_SIZE"TRUE"
CDS_LIB"pure_quanta"
CDS_LMAN_SYM_OUTLINE"-125,150,125,-150"
$SEC"1"
CDS_SEC"1";
"S"
$PN"S"25;
"G"
$PN"G"55;
"D"
$PN"D"56;
%"UNIVERSAL_GND"
"1","(2675,900)","0","logical_power","I317";
;
HDL_POWER"GND"
CDS_LIB"logical_power";
"A"25;
%"SCONN56_123276793"
"1","(500,3875)","0","pure_quanta","I318";
;
PART_NUMBER"DFHS56FS022"
VALUE"SCONN56_1-2327679-3"
MATERIAL"IO"
PART_TYPE"SMLF"
LOCATION"J90"
CDS_LMAN_SYM_OUTLINE"-575,875,575,-875"
NEEDS_NO_SIZE"TRUE"
CDS_LIB"pure_quanta"
$SEC"1"
CDS_SEC"1";
"G1"
$PN"G1"16;
"G2"
$PN"G2"17;
"PER_P3"
$PN"A27"64;
"PER_N3"
$PN"A26"63;
"PER_P2"
$PN"A24"78;
"PER_N2"
$PN"A23"58;
"PER_P1"
$PN"A21"48;
"PER_N1"
$PN"A20"65;
"PER_P0"
$PN"A18"47;
"PER_N0"
$PN"A17"46;
"REFCLK_P1"
$PN"A15"45;
"REFCLK_N1"
$PN"A14"35;
"GND_A28"
$PN"A28"16;
"GND_A25"
$PN"A25"16;
"GND_A22"
$PN"A22"16;
"GND_A19"
$PN"A19"16;
"GND_A16"
$PN"A16"16;
"GND_A13"
$PN"A13"16;
"PRSNT0# \B"
$PN"A12"33;
"PERST1#_CLKREQ# \B"
$PN"A11"34;
"PERST0# \B"
$PN"B10"43;
"LED#_ACTIVITY"
$PN"A10"36;
"SMBRST# \B"
$PN"A9"39;
"SMBDAT"
$PN"A8"37;
"SMBCLK"
$PN"A7"38;
"PET_P3"
$PN"B27"68;
"PET_N3"
$PN"B26"74;
"PET_P2"
$PN"B24"69;
"PET_N2"
$PN"B23"62;
"PET_P1"
$PN"B21"57;
"PET_N1"
$PN"B20"75;
"PET_P0"
$PN"B18"76;
"PET_N0"
$PN"B17"77;
"REFCLK_P0"
$PN"B15"60;
"REFCLK_N0"
$PN"B14"61;
"GND_B28"
$PN"B28"17;
"GND_B25"
$PN"B25"17;
"GND_B22"
$PN"B22"17;
"GND_B19"
$PN"B19"17;
"GND_B16"
$PN"B16"17;
"GND_B13"
$PN"B13"17;
"PWRDIS"
$PN"B12"44;
"P3V3_AUX"
$PN"B11"4;
"DUALPORTEN# \B"
$PN"B9"42;
"RFU"
$PN"B8"40;
"MFG"
$PN"B7"41;
"GND_A6"
$PN"A6"16;
"GND_A5"
$PN"A5"16;
"GND_A4"
$PN"A4"16;
"GND_A3"
$PN"A3"16;
"GND_A2"
$PN"A2"16;
"GND_A1"
$PN"A1"16;
"P12V_B6"
$PN"B6"6;
"P12V_B5"
$PN"B5"6;
"P12V_B4"
$PN"B4"6;
"P12V_B3"
$PN"B3"6;
"P12V_B2"
$PN"B2"6;
"P12V_B1"
$PN"B1"6;
%"TAP"
"1","(1675,3800)","0","standard","I319";
;
CDS_LIB"standard"
BODY_TYPE"PLUMBING"
HDL_TAP"TRUE";
"B \NAC \NWC"29;
"S \NAC"
BN"0"46;
%"TAP"
"1","(1825,3750)","0","standard","I320";
;
CDS_LIB"standard"
BODY_TYPE"PLUMBING"
HDL_TAP"TRUE";
"B \NAC \NWC"32;
"S \NAC"
BN"0"47;
%"TAP"
"1","(-625,3800)","2","standard","I321";
;
CDS_LIB"standard"
BODY_TYPE"PLUMBING"
HDL_TAP"TRUE";
"B \NAC \NWC"30;
"S \NAC"
BN"0"77;
%"TAP"
"1","(-775,3750)","2","standard","I322";
;
CDS_LIB"standard"
BODY_TYPE"PLUMBING"
HDL_TAP"TRUE";
"B \NAC \NWC"31;
"S \NAC"
BN"0"76;
%"TAP"
"1","(-625,3650)","2","standard","I324";
;
CDS_LIB"standard"
BODY_TYPE"PLUMBING"
HDL_TAP"TRUE";
"B \NAC \NWC"30;
"S \NAC"
BN"1"75;
%"TAP"
"1","(-775,3600)","2","standard","I325";
;
CDS_LIB"standard"
BODY_TYPE"PLUMBING"
HDL_TAP"TRUE";
"B \NAC \NWC"31;
"S \NAC"
BN"1"57;
%"UNIVERSAL_GND"
"1","(-3350,850)","0","logical_power","I326";
;
CDS_LIB"logical_power"
HDL_POWER"GND";
"A"28;
%"Q_CAP"
"1","(-3350,1075)","2","pure_quanta","I327";
;
PART_NUMBER"CH4104K1B00"
MATERIAL"X7R"
TOLERANCE"10%"
PACK_TYPE"0402"
VOLTAGE"25V"
VALUE"0.1UF"
$LOCATION"C2378"
CDS_LIB"pure_quanta"
CDS_LOCATION"C2378"
$SEC"1"
CDS_SEC"1";
"B"
$PN"2"28;
"A"
$PN"1"11;
%"UNIVERSAL_POWER"
"1","(-3350,1400)","0","logical_power","I328";
;
HDL_POWER"P3V3_E1S_0"
CDS_LIB"logical_power";
"A"11;
%"APX80929SAG7"
"1","(-2650,1250)","2","pure_quanta","I329";
;
PART_NUMBER"AL080929000"
PART_TYPE"SMLF"
MATERIAL"IC"
VALUE"APX809-29SAG-7"
$LOCATION"U336"
CDS_LIB"pure_quanta"
CDS_LMAN_SYM_OUTLINE"-225,200,225,-200"
NEEDS_NO_SIZE"TRUE"
CDS_LOCATION"U336"
$SEC"1"
CDS_SEC"1";
"GND"
$PN"1"27;
"RESET_L \B"
$PN"2"49;
"VCC"
$PN"3"11;
%"UNIVERSAL_GND"
"1","(-2150,1225)","0","logical_power","I330";
;
CDS_LIB"logical_power"
HDL_POWER"GND";
"A"27;
%"Q_RES"
"1","(-1400,1150)","0","pure_quanta","I331";
;
PART_NUMBER"CS04992FB07"
VALUE"49.9"
MATERIAL"CHIP"
$LOCATION"R4767"
CDS_LIB"pure_quanta"
PACK_TYPE"0402LF"
TOLERANCE"1%"
WATTAGE"1/16W"
CDS_LOCATION"R4767"
$SEC"1"
CDS_SEC"1";
"B"
$PN"2"50;
"A"
$PN"1"49;
END.
